# BASEBOARD_FAB2 (Tioga Pass) — schematic netlist excerpt (pin names and nets, part order shuffled) for the footprints in the layout excerpt that follows; sources: Cadence DE-HDL packaged netlist, KiCad conversion of Wiwynn_Tioga_Pass_MB.brd

R1C16  RES  1.5K 1% CHIP  pkg 0402  page 206 : A = VR_PVCCIN_CPU1_AVINSEN ; B = GND
R9F52  RES  4.75K 1% CHIP  pkg 0402  page 177 : A = P3V3_STBY ; B = FM_BMC_FAULT_LED
C2D25  CAP_A  22.0UF 4V 20% X6S  pkg 0603V  page 76 : A = PVCCIN_CPU1 ; B = GND

(kicad_pcb
	(version 20260206)
	(generator "pcbnew")
	(generator_version "10.0")
	(general
		(thickness 1.6)
		(legacy_teardrops no)
	)
	(paper "A4")
	(title_block
		(title "Wiwynn_Tioga_Pass_MB.brd")
		(comment 1 "Tioga Pass / footprints 460-462 of 4770")
	)
	(layers
		(0 "F.Cu" signal "TOP")
		(4 "In1.Cu" signal "L2GND")
		(6 "In2.Cu" signal "L3")
		(8 "In3.Cu" signal "L4GND")
		(10 "In4.Cu" signal "L5")
		(12 "In5.Cu" signal "L6GND")
		(14 "In6.Cu" signal "L7VCC")
		(16 "In7.Cu" signal "L8VCC")
		(18 "In8.Cu" signal "L9GND")
		(20 "In9.Cu" signal "L10")
		(22 "In10.Cu" signal "L11GND")
		(24 "In11.Cu" signal "L12")
		(26 "In12.Cu" signal "L13GND")
		(2 "B.Cu" signal "BOTTOM")
		(9 "F.Adhes" user "F.Adhesive")
		(11 "B.Adhes" user "B.Adhesive")
		(13 "F.Paste" user "Package Geometry/Pastemask Top")
		(15 "B.Paste" user "Package Geometry/Pastemask Bottom")
		(5 "F.SilkS" user "Ref Des/Silkscreen Top")
		(7 "B.SilkS" user "Ref Des/Silkscreen Bottom")
		(1 "F.Mask" user "Board Geometry/Soldermask Top")
		(3 "B.Mask" user "Board Geometry/Soldermask Bottom")
		(17 "Dwgs.User" user "User.Drawings")
		(19 "Cmts.User" user "User.Comments")
		(21 "Eco1.User" user "User.Eco1")
		(23 "Eco2.User" user "User.Eco2")
		(25 "Edge.Cuts" user "Board Geometry/Outline")
		(27 "Margin" user)
		(31 "F.CrtYd" user "Package Geometry/Place Bound Top")
		(29 "B.CrtYd" user "Package Geometry/Place Bound Bottom")
		(35 "F.Fab" user "Ref Des/Assembly Top")
		(33 "B.Fab" user "Ref Des/Assembly Bottom")
	)
	(footprint ""
		(layer "F.Cu")
		(at 100.67544 -77.636116)
		(property "Reference" "C2D25"
			(at 0 0 0)
			(layer "F.SilkS")
			(hide yes)
			(effects
				(font
					(size 1.27 1.27)
				)
			)
		)
		(property "Value" ""
			(at 0 0 0)
			(layer "F.Fab")
			(effects
				(font
					(size 1.27 1.27)
				)
			)
		)
		(duplicate_pad_numbers_are_jumpers no)
		(fp_poly
			(pts
				(xy -0.4953 -0.2032) (xy 0.4953 -0.2032) (xy 0.4953 1.6002) (xy -0.4953 1.6002)
			)
			(stroke
				(width 0)
				(type default)
			)
			(fill no)
			(layer "F.CrtYd")
		)
		(fp_line
			(start -0.4953 -0.2032)
			(end 0.4953 -0.2032)
			(stroke
				(width 0.1)
				(type default)
			)
			(layer "F.Fab")
		)
		(fp_line
			(start -0.4953 1.6002)
			(end -0.4953 -0.2032)
			(stroke
				(width 0.1)
				(type default)
			)
			(layer "F.Fab")
		)
		(fp_line
			(start 0.4953 -0.2032)
			(end 0.4953 1.6002)
			(stroke
				(width 0.1)
				(type default)
			)
			(layer "F.Fab")
		)
		(fp_line
			(start 0.4953 1.6002)
			(end -0.4953 1.6002)
			(stroke
				(width 0.1)
				(type default)
			)
			(layer "F.Fab")
		)
		(pad "1" smd rect
			(at 0 0)
			(size 0.762 0.889)
			(layers "F.Cu" "F.Mask" "F.Paste")
			(net "PVCCIN_CPU1")
		)
		(pad "2" smd rect
			(at 0 1.397)
			(size 0.762 0.889)
			(layers "F.Cu" "F.Mask" "F.Paste")
			(net "GND")
		)
		(zone
			(layer "F.Cu")
			(hatch none 0.5)
			(connect_pads
				(clearance 0)
			)
			(min_thickness 0.25)
			(keepout
				(tracks not_allowed)
				(vias allowed)
				(pads allowed)
				(copperpour not_allowed)
				(footprints allowed)
			)
			(placement
				(enabled no)
				(sheetname "")
			)
			(fill
				(thermal_gap 0.5)
				(thermal_bridge_width 0.5)
				(island_removal_mode 0)
			)
			(polygon
				(pts
					(xy 100.29444 -77.191616) (xy 101.05644 -77.191616) (xy 101.05644 -76.683616) (xy 100.29444 -76.683616)
				)
			)
		)
	)
	(footprint ""
		(layer "F.Cu")
		(at 18.288 -98.7044 -90)
		(property "Reference" "R1C16"
			(at 0 0 270)
			(layer "F.SilkS")
			(hide yes)
			(effects
				(font
					(size 1.27 1.27)
				)
			)
		)
		(property "Value" ""
			(at 0 0 270)
			(layer "F.Fab")
			(effects
				(font
					(size 1.27 1.27)
				)
			)
		)
		(duplicate_pad_numbers_are_jumpers no)
		(fp_poly
			(pts
				(xy -0.2794 -0.1016) (xy 0.2794 -0.1016) (xy 0.2794 0.9906) (xy -0.2794 0.9906)
			)
			(stroke
				(width 0)
				(type default)
			)
			(fill no)
			(layer "F.CrtYd")
		)
		(fp_line
			(start -0.2794 0.9906)
			(end 0.2794 0.9906)
			(stroke
				(width 0.1)
				(type default)
			)
			(layer "F.Fab")
		)
		(fp_line
			(start 0.2794 0.9906)
			(end 0.2794 -0.1016)
			(stroke
				(width 0.1)
				(type default)
			)
			(layer "F.Fab")
		)
		(fp_line
			(start -0.2794 -0.1016)
			(end -0.2794 0.9906)
			(stroke
				(width 0.1)
				(type default)
			)
			(layer "F.Fab")
		)
		(fp_line
			(start 0.2794 -0.1016)
			(end -0.2794 -0.1016)
			(stroke
				(width 0.1)
				(type default)
			)
			(layer "F.Fab")
		)
		(pad "1" smd rect
			(at 0 0 270)
			(size 0.508 0.508)
			(layers "F.Cu" "F.Mask" "F.Paste")
			(net "VR_PVCCIN_CPU1_AVINSEN")
		)
		(pad "2" smd rect
			(at 0 0.889 270)
			(size 0.508 0.508)
			(layers "F.Cu" "F.Mask" "F.Paste")
			(net "GND")
		)
		(zone
			(layer "F.Cu")
			(hatch none 0.5)
			(connect_pads
				(clearance 0)
			)
			(min_thickness 0.25)
			(keepout
				(tracks not_allowed)
				(vias allowed)
				(pads allowed)
				(copperpour not_allowed)
				(footprints allowed)
			)
			(placement
				(enabled no)
				(sheetname "")
			)
			(fill
				(thermal_gap 0.5)
				(thermal_bridge_width 0.5)
				(island_removal_mode 0)
			)
			(polygon
				(pts
					(xy 17.653 -98.9584) (xy 17.653 -98.4504) (xy 18.034 -98.4504) (xy 18.034 -98.9584)
				)
			)
		)
		(zone
			(layer "F.Cu")
			(hatch none 0.5)
			(connect_pads
				(clearance 0)
			)
			(min_thickness 0.25)
			(keepout
				(tracks allowed)
				(vias not_allowed)
				(pads allowed)
				(copperpour not_allowed)
				(footprints allowed)
			)
			(placement
				(enabled no)
				(sheetname "")
			)
			(fill
				(thermal_gap 0.5)
				(thermal_bridge_width 0.5)
				(island_removal_mode 0)
			)
			(polygon
				(pts
					(xy 18.034 -98.9584) (xy 18.034 -98.4504) (xy 17.653 -98.4504) (xy 17.653 -98.9584)
				)
			)
		)
	)
	(footprint ""
		(layer "F.Cu")
		(at 457.0095 -30.48 90)
		(property "Reference" "R9F52"
			(at 0 0 90)
			(layer "F.SilkS")
			(hide yes)
			(effects
				(font
					(size 1.27 1.27)
				)
			)
		)
		(property "Value" ""
			(at 0 0 90)
			(layer "F.Fab")
			(effects
				(font
					(size 1.27 1.27)
				)
			)
		)
		(duplicate_pad_numbers_are_jumpers no)
		(fp_poly
			(pts
				(xy -0.2794 -0.1016) (xy 0.2794 -0.1016) (xy 0.2794 0.9906) (xy -0.2794 0.9906)
			)
			(stroke
				(width 0)
				(type default)
			)
			(fill no)
			(layer "F.CrtYd")
		)
		(fp_line
			(start 0.2794 -0.1016)
			(end -0.2794 -0.1016)
			(stroke
				(width 0.1)
				(type default)
			)
			(layer "F.Fab")
		)
		(fp_line
			(start -0.2794 -0.1016)
			(end -0.2794 0.9906)
			(stroke
				(width 0.1)
				(type default)
			)
			(layer "F.Fab")
		)
		(fp_line
			(start 0.2794 0.9906)
			(end 0.2794 -0.1016)
			(stroke
				(width 0.1)
				(type default)
			)
			(layer "F.Fab")
		)
		(fp_line
			(start -0.2794 0.9906)
			(end 0.2794 0.9906)
			(stroke
				(width 0.1)
				(type default)
			)
			(layer "F.Fab")
		)
		(pad "1" smd rect
			(at 0 0 90)
			(size 0.508 0.508)
			(layers "F.Cu" "F.Mask" "F.Paste")
			(net "P3V3_STBY")
		)
		(pad "2" smd rect
			(at 0 0.889 90)
			(size 0.508 0.508)
			(layers "F.Cu" "F.Mask" "F.Paste")
			(net "FM_BMC_FAULT_LED")
		)
		(zone
			(layer "F.Cu")
			(hatch none 0.5)
			(connect_pads
				(clearance 0)
			)
			(min_thickness 0.25)
			(keepout
				(tracks allowed)
				(vias not_allowed)
				(pads allowed)
				(copperpour not_allowed)
				(footprints allowed)
			)
			(placement
				(enabled no)
				(sheetname "")
			)
			(fill
				(thermal_gap 0.5)
				(thermal_bridge_width 0.5)
				(island_removal_mode 0)
			)
			(polygon
				(pts
					(xy 457.2635 -30.226) (xy 457.2635 -30.734) (xy 457.6445 -30.734) (xy 457.6445 -30.226)
				)
			)
		)
		(zone
			(layer "F.Cu")
			(hatch none 0.5)
			(connect_pads
				(clearance 0)
			)
			(min_thickness 0.25)
			(keepout
				(tracks not_allowed)
				(vias allowed)
				(pads allowed)
				(copperpour not_allowed)
				(footprints allowed)
			)
			(placement
				(enabled no)
				(sheetname "")
			)
			(fill
				(thermal_gap 0.5)
				(thermal_bridge_width 0.5)
				(island_removal_mode 0)
			)
			(polygon
				(pts
					(xy 457.6445 -30.226) (xy 457.6445 -30.734) (xy 457.2635 -30.734) (xy 457.2635 -30.226)
				)
			)
		)
	)
)
